(kicad_pcb
	(version 20260206)
	(generator "pcbnew")
	(generator_version "10.0")
	(general
		(thickness 1.6)
		(legacy_teardrops no)
	)
	(paper "A4")
	(title_block
		(title "01162023_DA0F0TEBIF0_F0T_Expander_BD_F_brd_V02_OCP.brd")
		(comment 1 "Grand Teton / footprints 6246-6252 of 9728")
	)
	(layers
		(0 "F.Cu" signal "TOP")
		(4 "In1.Cu" signal "GND")
		(6 "In2.Cu" signal "VCC")
		(8 "In3.Cu" signal "VCC1")
		(10 "In4.Cu" signal "GND1")
		(12 "In5.Cu" signal "IN1")
		(14 "In6.Cu" signal "GND2")
		(16 "In7.Cu" signal "IN2")
		(18 "In8.Cu" signal "GND3")
		(20 "In9.Cu" signal "IN3")
		(22 "In10.Cu" signal "GND4")
		(24 "In11.Cu" signal "IN4")
		(26 "In12.Cu" signal "GND5")
		(28 "In13.Cu" signal "IN5")
		(30 "In14.Cu" signal "GND6")
		(32 "In15.Cu" signal "IN6")
		(34 "In16.Cu" signal "GND7")
		(2 "B.Cu" signal "BOTTOM")
		(9 "F.Adhes" user "F.Adhesive")
		(11 "B.Adhes" user "B.Adhesive")
		(13 "F.Paste" user "Package Geometry/Pastemask Top")
		(15 "B.Paste" user "Package Geometry/Pastemask Bottom")
		(5 "F.SilkS" user "Ref Des/Silkscreen Top")
		(7 "B.SilkS" user "Ref Des/Silkscreen Bottom")
		(1 "F.Mask" user "Board Geometry/Soldermask Top")
		(3 "B.Mask" user "Board Geometry/Soldermask Bottom")
		(17 "Dwgs.User" user "User.Drawings")
		(19 "Cmts.User" user "User.Comments")
		(21 "Eco1.User" user "User.Eco1")
		(23 "Eco2.User" user "User.Eco2")
		(25 "Edge.Cuts" user "Board Geometry/Outline")
		(27 "Margin" user)
		(31 "F.CrtYd" user "Package Geometry/Place Bound Top")
		(29 "B.CrtYd" user "Package Geometry/Place Bound Bottom")
		(35 "F.Fab" user "Ref Des/Assembly Top")
		(33 "B.Fab" user "Ref Des/Assembly Bottom")
	)
	(footprint ""
		(layer "F.Cu")
		(at 332.994 -245.237 90)
		(property "Reference" "R1798"
			(at 0 0 90)
			(layer "F.SilkS")
			(hide yes)
			(effects
				(font
					(size 1.27 1.27)
				)
			)
		)
		(property "Value" ""
			(at 0 0 90)
			(layer "F.Fab")
			(effects
				(font
					(size 1.27 1.27)
				)
			)
		)
		(duplicate_pad_numbers_are_jumpers no)
		(fp_line
			(start 0.7874 -0.4064)
			(end 0.7874 0.4064)
			(stroke
				(width 0.1524)
				(type default)
			)
			(layer "F.SilkS")
		)
		(fp_line
			(start -0.7874 -0.4064)
			(end 0.7874 -0.4064)
			(stroke
				(width 0.1524)
				(type default)
			)
			(layer "F.SilkS")
		)
		(fp_line
			(start 0.7874 0.4064)
			(end -0.7874 0.4064)
			(stroke
				(width 0.1524)
				(type default)
			)
			(layer "F.SilkS")
		)
		(fp_line
			(start -0.7874 0.4064)
			(end -0.7874 -0.4064)
			(stroke
				(width 0.1524)
				(type default)
			)
			(layer "F.SilkS")
		)
		(fp_line
			(start -0.12065 -0.305054)
			(end -0.12065 -0.2794)
			(stroke
				(width 0.1)
				(type default)
			)
			(layer "F.Fab")
		)
		(fp_line
			(start -0.67945 -0.305054)
			(end -0.12065 -0.305054)
			(stroke
				(width 0.1)
				(type default)
			)
			(layer "F.Fab")
		)
		(fp_line
			(start 0.67945 -0.3048)
			(end 0.67945 0.3048)
			(stroke
				(width 0.1)
				(type default)
			)
			(layer "F.Fab")
		)
		(fp_line
			(start 0.12065 -0.3048)
			(end 0.67945 -0.3048)
			(stroke
				(width 0.1)
				(type default)
			)
			(layer "F.Fab")
		)
		(fp_line
			(start 0.12065 -0.2794)
			(end 0.12065 -0.3048)
			(stroke
				(width 0.1)
				(type default)
			)
			(layer "F.Fab")
		)
		(fp_line
			(start -0.12065 -0.2794)
			(end 0.12065 -0.2794)
			(stroke
				(width 0.1)
				(type default)
			)
			(layer "F.Fab")
		)
		(fp_line
			(start 0.120396 0.2794)
			(end -0.12065 0.2794)
			(stroke
				(width 0.1)
				(type default)
			)
			(layer "F.Fab")
		)
		(fp_line
			(start -0.12065 0.2794)
			(end -0.12065 0.3048)
			(stroke
				(width 0.1)
				(type default)
			)
			(layer "F.Fab")
		)
		(fp_line
			(start 0.67945 0.3048)
			(end 0.120396 0.3048)
			(stroke
				(width 0.1)
				(type default)
			)
			(layer "F.Fab")
		)
		(fp_line
			(start 0.120396 0.3048)
			(end 0.120396 0.2794)
			(stroke
				(width 0.1)
				(type default)
			)
			(layer "F.Fab")
		)
		(fp_line
			(start -0.12065 0.3048)
			(end -0.67945 0.3048)
			(stroke
				(width 0.1)
				(type default)
			)
			(layer "F.Fab")
		)
		(fp_line
			(start -0.67945 0.3048)
			(end -0.67945 -0.305054)
			(stroke
				(width 0.1)
				(type default)
			)
			(layer "F.Fab")
		)
		(pad "1" smd circle
			(at -0.40005 0 90)
			(size 0 0)
			(layers "F.Cu" "F.Mask" "F.Paste")
			(net "P3V3_AUX")
		)
		(pad "2" smd circle
			(at 0.40005 0 90)
			(size 0 0)
			(layers "F.Cu" "F.Mask" "F.Paste")
			(net "MB_SWB_PWRGD_BUF_R")
		)
	)
	(footprint ""
		(layer "F.Cu")
		(at 3.631692 -377.270518)
		(property "Reference" "Y9"
			(at 0.801624 3.378962 0)
			(unlocked yes)
			(layer "F.SilkS")
			(effects
				(font
					(size 0.7874 0.5842)
					(thickness 0.1524)
				)
				(justify left)
			)
		)
		(property "Value" ""
			(at 0 0 0)
			(layer "F.Fab")
			(effects
				(font
					(size 1.27 1.27)
				)
			)
		)
		(duplicate_pad_numbers_are_jumpers no)
		(fp_line
			(start -1.6002 -1.9558)
			(end 1.6002 -1.9558)
			(stroke
				(width 0.1524)
				(type default)
			)
			(layer "F.SilkS")
		)
		(fp_line
			(start -1.6002 1.9558)
			(end -1.6002 -1.9558)
			(stroke
				(width 0.1524)
				(type default)
			)
			(layer "F.SilkS")
		)
		(fp_line
			(start 1.6002 -1.9558)
			(end 1.6002 1.9558)
			(stroke
				(width 0.1524)
				(type default)
			)
			(layer "F.SilkS")
		)
		(fp_line
			(start 1.6002 1.9558)
			(end -1.6002 1.9558)
			(stroke
				(width 0.1524)
				(type default)
			)
			(layer "F.SilkS")
		)
		(fp_poly
			(pts
				(xy -1.7145 -1.0668) (xy -2.8067 -1.651) (xy -2.8067 -0.5842)
			)
			(stroke
				(width 0)
				(type default)
			)
			(fill yes)
			(layer "F.SilkS")
		)
		(fp_line
			(start -1.299972 -1.649984)
			(end 1.299972 -1.649984)
			(stroke
				(width 0.1)
				(type default)
			)
			(layer "F.Fab")
		)
		(fp_line
			(start -1.299972 1.649984)
			(end -1.299972 -1.649984)
			(stroke
				(width 0.1)
				(type default)
			)
			(layer "F.Fab")
		)
		(fp_line
			(start 1.299972 -1.649984)
			(end 1.299972 1.649984)
			(stroke
				(width 0.1)
				(type default)
			)
			(layer "F.Fab")
		)
		(fp_line
			(start 1.299972 1.649984)
			(end -1.299972 1.649984)
			(stroke
				(width 0.1)
				(type default)
			)
			(layer "F.Fab")
		)
		(fp_poly
			(pts
				(xy -1.7145 -1.0668) (xy -2.8067 -1.651) (xy -2.8067 -0.5842)
			)
			(stroke
				(width 0)
				(type default)
			)
			(fill yes)
			(layer "F.Fab")
		)
		(pad "1" smd rect
			(at -0.849884 -1.100074)
			(size 1.2192 1.4224)
			(layers "F.Cu" "F.Mask" "F.Paste")
			(net "BIC_USB_8042_HUB_XOUT")
		)
		(pad "2" smd rect
			(at -0.849884 1.100074)
			(size 1.2192 1.4224)
			(layers "F.Cu" "F.Mask" "F.Paste")
			(net "GND")
		)
		(pad "3" smd rect
			(at 0.849884 1.100074)
			(size 1.2192 1.4224)
			(layers "F.Cu" "F.Mask" "F.Paste")
			(net "BIC_USB_8042_HUB_XIN")
		)
		(pad "4" smd rect
			(at 0.849884 -1.100074)
			(size 1.2192 1.4224)
			(layers "F.Cu" "F.Mask" "F.Paste")
			(net "GND")
		)
	)
	(footprint ""
		(layer "F.Cu")
		(at 444.09233 -31.825184 180)
		(property "Reference" "C725"
			(at 0 0 180)
			(layer "F.SilkS")
			(hide yes)
			(effects
				(font
					(size 1.27 1.27)
				)
			)
		)
		(property "Value" ""
			(at 0 0 180)
			(layer "F.Fab")
			(effects
				(font
					(size 1.27 1.27)
				)
			)
		)
		(duplicate_pad_numbers_are_jumpers no)
		(fp_line
			(start 0.299974 0.150114)
			(end -0.299974 0.150114)
			(stroke
				(width 0.1)
				(type default)
			)
			(layer "F.Fab")
		)
		(fp_line
			(start 0.299974 -0.150114)
			(end 0.299974 0.150114)
			(stroke
				(width 0.1)
				(type default)
			)
			(layer "F.Fab")
		)
		(fp_line
			(start -0.299974 0.150114)
			(end -0.299974 -0.150114)
			(stroke
				(width 0.1)
				(type default)
			)
			(layer "F.Fab")
		)
		(fp_line
			(start -0.299974 -0.150114)
			(end 0.299974 -0.150114)
			(stroke
				(width 0.1)
				(type default)
			)
			(layer "F.Fab")
		)
		(pad "1" smd rect
			(at -0.2667 0 180)
			(size 0.3048 0.381)
			(layers "F.Cu" "F.Mask" "F.Paste")
			(net "P5E_PEX3_STN2_TX_DN<34>")
		)
		(pad "2" smd rect
			(at 0.2667 0 180)
			(size 0.3048 0.381)
			(layers "F.Cu" "F.Mask" "F.Paste")
			(net "P5E_PEX3_STN2_TX_C_DN<34>")
		)
	)
	(footprint ""
		(layer "F.Cu")
		(at 198.93661 -368.5921 -90)
		(property "Reference" "PC5"
			(at 0 0 270)
			(layer "F.SilkS")
			(hide yes)
			(effects
				(font
					(size 1.27 1.27)
				)
			)
		)
		(property "Value" ""
			(at 0 0 270)
			(layer "F.Fab")
			(effects
				(font
					(size 1.27 1.27)
				)
			)
		)
		(duplicate_pad_numbers_are_jumpers no)
		(fp_line
			(start -0.7874 0.4064)
			(end -0.7874 -0.4064)
			(stroke
				(width 0.1524)
				(type default)
			)
			(layer "F.SilkS")
		)
		(fp_line
			(start 0.7874 0.4064)
			(end -0.7874 0.4064)
			(stroke
				(width 0.1524)
				(type default)
			)
			(layer "F.SilkS")
		)
		(fp_line
			(start -0.7874 -0.4064)
			(end 0.7874 -0.4064)
			(stroke
				(width 0.1524)
				(type default)
			)
			(layer "F.SilkS")
		)
		(fp_line
			(start 0.7874 -0.4064)
			(end 0.7874 0.4064)
			(stroke
				(width 0.1524)
				(type default)
			)
			(layer "F.SilkS")
		)
		(fp_line
			(start -0.67945 0.3048)
			(end -0.67945 -0.305054)
			(stroke
				(width 0.1)
				(type default)
			)
			(layer "F.Fab")
		)
		(fp_line
			(start -0.12065 0.3048)
			(end -0.67945 0.3048)
			(stroke
				(width 0.1)
				(type default)
			)
			(layer "F.Fab")
		)
		(fp_line
			(start 0.120396 0.3048)
			(end 0.120396 0.2794)
			(stroke
				(width 0.1)
				(type default)
			)
			(layer "F.Fab")
		)
		(fp_line
			(start 0.67945 0.3048)
			(end 0.120396 0.3048)
			(stroke
				(width 0.1)
				(type default)
			)
			(layer "F.Fab")
		)
		(fp_line
			(start -0.12065 0.2794)
			(end -0.12065 0.3048)
			(stroke
				(width 0.1)
				(type default)
			)
			(layer "F.Fab")
		)
		(fp_line
			(start 0.120396 0.2794)
			(end -0.12065 0.2794)
			(stroke
				(width 0.1)
				(type default)
			)
			(layer "F.Fab")
		)
		(fp_line
			(start -0.12065 -0.2794)
			(end 0.12065 -0.2794)
			(stroke
				(width 0.1)
				(type default)
			)
			(layer "F.Fab")
		)
		(fp_line
			(start 0.12065 -0.2794)
			(end 0.12065 -0.3048)
			(stroke
				(width 0.1)
				(type default)
			)
			(layer "F.Fab")
		)
		(fp_line
			(start 0.12065 -0.3048)
			(end 0.67945 -0.3048)
			(stroke
				(width 0.1)
				(type default)
			)
			(layer "F.Fab")
		)
		(fp_line
			(start 0.67945 -0.3048)
			(end 0.67945 0.3048)
			(stroke
				(width 0.1)
				(type default)
			)
			(layer "F.Fab")
		)
		(fp_line
			(start -0.67945 -0.305054)
			(end -0.12065 -0.305054)
			(stroke
				(width 0.1)
				(type default)
			)
			(layer "F.Fab")
		)
		(fp_line
			(start -0.12065 -0.305054)
			(end -0.12065 -0.2794)
			(stroke
				(width 0.1)
				(type default)
			)
			(layer "F.Fab")
		)
		(pad "1" smd circle
			(at -0.40005 0 270)
			(size 0 0)
			(layers "F.Cu" "F.Mask" "F.Paste")
			(net "HSC_VDD_R")
		)
		(pad "2" smd circle
			(at 0.40005 0 270)
			(size 0 0)
			(layers "F.Cu" "F.Mask" "F.Paste")
			(net "AGND_HSC")
		)
	)
	(footprint ""
		(layer "F.Cu")
		(at 38.608 -157.3784 180)
		(property "Reference" "R12"
			(at 0 0 180)
			(layer "F.SilkS")
			(hide yes)
			(effects
				(font
					(size 1.27 1.27)
				)
			)
		)
		(property "Value" ""
			(at 0 0 180)
			(layer "F.Fab")
			(effects
				(font
					(size 1.27 1.27)
				)
			)
		)
		(duplicate_pad_numbers_are_jumpers no)
		(fp_line
			(start 0.7874 0.4064)
			(end -0.7874 0.4064)
			(stroke
				(width 0.1524)
				(type default)
			)
			(layer "F.SilkS")
		)
		(fp_line
			(start 0.7874 -0.4064)
			(end 0.7874 0.4064)
			(stroke
				(width 0.1524)
				(type default)
			)
			(layer "F.SilkS")
		)
		(fp_line
			(start -0.7874 0.4064)
			(end -0.7874 -0.4064)
			(stroke
				(width 0.1524)
				(type default)
			)
			(layer "F.SilkS")
		)
		(fp_line
			(start -0.7874 -0.4064)
			(end 0.7874 -0.4064)
			(stroke
				(width 0.1524)
				(type default)
			)
			(layer "F.SilkS")
		)
		(fp_line
			(start 0.67945 0.3048)
			(end 0.120396 0.3048)
			(stroke
				(width 0.1)
				(type default)
			)
			(layer "F.Fab")
		)
		(fp_line
			(start 0.67945 -0.3048)
			(end 0.67945 0.3048)
			(stroke
				(width 0.1)
				(type default)
			)
			(layer "F.Fab")
		)
		(fp_line
			(start 0.12065 -0.2794)
			(end 0.12065 -0.3048)
			(stroke
				(width 0.1)
				(type default)
			)
			(layer "F.Fab")
		)
		(fp_line
			(start 0.12065 -0.3048)
			(end 0.67945 -0.3048)
			(stroke
				(width 0.1)
				(type default)
			)
			(layer "F.Fab")
		)
		(fp_line
			(start 0.120396 0.3048)
			(end 0.120396 0.2794)
			(stroke
				(width 0.1)
				(type default)
			)
			(layer "F.Fab")
		)
		(fp_line
			(start 0.120396 0.2794)
			(end -0.12065 0.2794)
			(stroke
				(width 0.1)
				(type default)
			)
			(layer "F.Fab")
		)
		(fp_line
			(start -0.12065 0.3048)
			(end -0.67945 0.3048)
			(stroke
				(width 0.1)
				(type default)
			)
			(layer "F.Fab")
		)
		(fp_line
			(start -0.12065 0.2794)
			(end -0.12065 0.3048)
			(stroke
				(width 0.1)
				(type default)
			)
			(layer "F.Fab")
		)
		(fp_line
			(start -0.12065 -0.2794)
			(end 0.12065 -0.2794)
			(stroke
				(width 0.1)
				(type default)
			)
			(layer "F.Fab")
		)
		(fp_line
			(start -0.12065 -0.305054)
			(end -0.12065 -0.2794)
			(stroke
				(width 0.1)
				(type default)
			)
			(layer "F.Fab")
		)
		(fp_line
			(start -0.67945 0.3048)
			(end -0.67945 -0.305054)
			(stroke
				(width 0.1)
				(type default)
			)
			(layer "F.Fab")
		)
		(fp_line
			(start -0.67945 -0.305054)
			(end -0.12065 -0.305054)
			(stroke
				(width 0.1)
				(type default)
			)
			(layer "F.Fab")
		)
		(pad "1" smd circle
			(at -0.40005 0 180)
			(size 0 0)
			(layers "F.Cu" "F.Mask" "F.Paste")
			(net "NIC0_DATA_IN")
		)
		(pad "2" smd circle
			(at 0.40005 0 180)
			(size 0 0)
			(layers "F.Cu" "F.Mask" "F.Paste")
			(net "P3V3_NIC0")
		)
	)
	(footprint ""
		(layer "F.Cu")
		(at 5.617718 -264.586466 180)
		(property "Reference" "R6127"
			(at 0 0 180)
			(layer "F.SilkS")
			(hide yes)
			(effects
				(font
					(size 1.27 1.27)
				)
			)
		)
		(property "Value" ""
			(at 0 0 180)
			(layer "F.Fab")
			(effects
				(font
					(size 1.27 1.27)
				)
			)
		)
		(duplicate_pad_numbers_are_jumpers no)
		(fp_line
			(start 2.576322 1.1303)
			(end -2.576322 1.1303)
			(stroke
				(width 0.1524)
				(type default)
			)
			(layer "F.SilkS")
		)
		(fp_line
			(start 2.576322 -1.1303)
			(end 2.576322 1.1303)
			(stroke
				(width 0.1524)
				(type default)
			)
			(layer "F.SilkS")
		)
		(fp_line
			(start -2.576322 1.1303)
			(end -2.576322 -1.1303)
			(stroke
				(width 0.1524)
				(type default)
			)
			(layer "F.SilkS")
		)
		(fp_line
			(start -2.576322 -1.1303)
			(end 2.576322 -1.1303)
			(stroke
				(width 0.1524)
				(type default)
			)
			(layer "F.SilkS")
		)
		(fp_line
			(start 1.649984 0.899922)
			(end 1.649984 -0.899922)
			(stroke
				(width 0.1)
				(type default)
			)
			(layer "F.Fab")
		)
		(fp_line
			(start 1.649984 -0.899922)
			(end -1.649984 -0.899922)
			(stroke
				(width 0.1)
				(type default)
			)
			(layer "F.Fab")
		)
		(fp_line
			(start -1.649984 0.899922)
			(end 1.649984 0.899922)
			(stroke
				(width 0.1)
				(type default)
			)
			(layer "F.Fab")
		)
		(fp_line
			(start -1.649984 -0.899922)
			(end -1.649984 0.899922)
			(stroke
				(width 0.1)
				(type default)
			)
			(layer "F.Fab")
		)
		(pad "1A" smd rect
			(at -1.700022 0 180)
			(size 1.4986 2.0066)
			(layers "F.Cu" "F.Mask" "F.Paste")
			(net "P1V25_PEX0")
		)
		(pad "1B" smd rect
			(at -1.077722 0 180)
			(size 0.254 0.508)
			(layers "F.Cu" "F.Mask" "F.Paste")
			(net "P1V25_PEX0")
		)
		(pad "2A" smd rect
			(at 1.700022 0 180)
			(size 1.4986 2.0066)
			(layers "F.Cu" "F.Mask" "F.Paste")
			(net "P1V25_SERDES_VDDPLL_PEX0")
		)
		(pad "2B" smd rect
			(at 1.077722 0 180)
			(size 0.254 0.508)
			(layers "F.Cu" "F.Mask" "F.Paste")
			(net "P1V25_SERDES_VDDPLL_PEX0")
		)
	)
	(footprint ""
		(layer "F.Cu")
		(at 425.36237 -22.955504 -90)
		(property "Reference" "C2733"
			(at 0 0 270)
			(layer "F.SilkS")
			(hide yes)
			(effects
				(font
					(size 1.27 1.27)
				)
			)
		)
		(property "Value" ""
			(at 0 0 270)
			(layer "F.Fab")
			(effects
				(font
					(size 1.27 1.27)
				)
			)
		)
		(duplicate_pad_numbers_are_jumpers no)
		(fp_line
			(start -0.7874 0.4064)
			(end -0.7874 -0.4064)
			(stroke
				(width 0.1524)
				(type default)
			)
			(layer "F.SilkS")
		)
		(fp_line
			(start 0.7874 0.4064)
			(end -0.7874 0.4064)
			(stroke
				(width 0.1524)
				(type default)
			)
			(layer "F.SilkS")
		)
		(fp_line
			(start -0.7874 -0.4064)
			(end 0.7874 -0.4064)
			(stroke
				(width 0.1524)
				(type default)
			)
			(layer "F.SilkS")
		)
		(fp_line
			(start 0.7874 -0.4064)
			(end 0.7874 0.4064)
			(stroke
				(width 0.1524)
				(type default)
			)
			(layer "F.SilkS")
		)
		(fp_line
			(start -0.67945 0.3048)
			(end -0.67945 -0.305054)
			(stroke
				(width 0.1)
				(type default)
			)
			(layer "F.Fab")
		)
		(fp_line
			(start -0.12065 0.3048)
			(end -0.67945 0.3048)
			(stroke
				(width 0.1)
				(type default)
			)
			(layer "F.Fab")
		)
		(fp_line
			(start 0.120396 0.3048)
			(end 0.120396 0.2794)
			(stroke
				(width 0.1)
				(type default)
			)
			(layer "F.Fab")
		)
		(fp_line
			(start 0.67945 0.3048)
			(end 0.120396 0.3048)
			(stroke
				(width 0.1)
				(type default)
			)
			(layer "F.Fab")
		)
		(fp_line
			(start -0.12065 0.2794)
			(end -0.12065 0.3048)
			(stroke
				(width 0.1)
				(type default)
			)
			(layer "F.Fab")
		)
		(fp_line
			(start 0.120396 0.2794)
			(end -0.12065 0.2794)
			(stroke
				(width 0.1)
				(type default)
			)
			(layer "F.Fab")
		)
		(fp_line
			(start -0.12065 -0.2794)
			(end 0.12065 -0.2794)
			(stroke
				(width 0.1)
				(type default)
			)
			(layer "F.Fab")
		)
		(fp_line
			(start 0.12065 -0.2794)
			(end 0.12065 -0.3048)
			(stroke
				(width 0.1)
				(type default)
			)
			(layer "F.Fab")
		)
		(fp_line
			(start 0.12065 -0.3048)
			(end 0.67945 -0.3048)
			(stroke
				(width 0.1)
				(type default)
			)
			(layer "F.Fab")
		)
		(fp_line
			(start 0.67945 -0.3048)
			(end 0.67945 0.3048)
			(stroke
				(width 0.1)
				(type default)
			)
			(layer "F.Fab")
		)
		(fp_line
			(start -0.67945 -0.305054)
			(end -0.12065 -0.305054)
			(stroke
				(width 0.1)
				(type default)
			)
			(layer "F.Fab")
		)
		(fp_line
			(start -0.12065 -0.305054)
			(end -0.12065 -0.2794)
			(stroke
				(width 0.1)
				(type default)
			)
			(layer "F.Fab")
		)
		(pad "1" smd circle
			(at -0.40005 0 270)
			(size 0 0)
			(layers "F.Cu" "F.Mask" "F.Paste")
			(net "GND")
		)
		(pad "2" smd circle
			(at 0.40005 0 270)
			(size 0 0)
			(layers "F.Cu" "F.Mask" "F.Paste")
			(net "P3V3_AUX")
		)
	)
)
